# TIMECARD (Time Appliance Project (Time Card)) — schematic netlist excerpt (pin names and nets, part order shuffled) for the footprints in the layout excerpt that follows; sources: Cadence DE-HDL packaged netlist, KiCad conversion of R4006-B0001-02_R01.brd

CR7  DIODE_4_V1  pkg SOT143  page 10
  GND  = SG
  IO1  = FT4232_FPGA_TCK
  IO2  = FT4232_FPGA_TDO
  VDD  = NC

(kicad_pcb
	(version 20260206)
	(generator "pcbnew")
	(generator_version "10.0")
	(general
		(thickness 1.6)
		(legacy_teardrops no)
	)
	(paper "A4")
	(title_block
		(title "timecard-production-celestica-r4006 — R4006-B0001-02_R01.brd")
		(comment 1 "Time Appliance Project (Time Card) / footprints 812-812 of 1113")
	)
	(layers
		(0 "F.Cu" signal "TOP")
		(4 "In1.Cu" signal "L02_GND1")
		(6 "In2.Cu" signal "L03_SIG1")
		(8 "In3.Cu" signal "L04_GND2")
		(10 "In4.Cu" signal "L05_VCC1")
		(12 "In5.Cu" signal "L06_VCC2")
		(14 "In6.Cu" signal "L07_GND3")
		(16 "In7.Cu" signal "L08_SIG2")
		(18 "In8.Cu" signal "L09_GND4")
		(2 "B.Cu" signal "BOTTOM")
		(9 "F.Adhes" user "F.Adhesive")
		(11 "B.Adhes" user "B.Adhesive")
		(13 "F.Paste" user "Package Geometry/Pastemask Top")
		(15 "B.Paste" user "Package Geometry/Pastemask Bottom")
		(5 "F.SilkS" user "Ref Des/Silkscreen Top")
		(7 "B.SilkS" user "Ref Des/Silkscreen Bottom")
		(1 "F.Mask" user "Board Geometry/Soldermask Top")
		(3 "B.Mask" user "Board Geometry/Soldermask Bottom")
		(17 "Dwgs.User" user "User.Drawings")
		(19 "Cmts.User" user "User.Comments")
		(21 "Eco1.User" user "User.Eco1")
		(23 "Eco2.User" user "User.Eco2")
		(25 "Edge.Cuts" user "Board Geometry/Outline")
		(27 "Margin" user)
		(31 "F.CrtYd" user "Package Geometry/Place Bound Top")
		(29 "B.CrtYd" user "Package Geometry/Place Bound Bottom")
		(35 "F.Fab" user "Ref Des/Assembly Top")
		(33 "B.Fab" user "Ref Des/Assembly Bottom")
	)
	(footprint ""
		(layer "B.Cu")
		(at 145.1102 -68.0974 -90)
		(property "Reference" "CR7"
			(at -3.11023 -0.0508 0)
			(unlocked yes)
			(layer "B.SilkS")
			(effects
				(font
					(size 0.7874 0.5842)
					(thickness 0.1524)
				)
				(justify mirror)
			)
		)
		(property "Value" ""
			(at 0 0 90)
			(layer "B.Fab")
			(effects
				(font
					(size 1.27 1.27)
				)
				(justify mirror)
			)
		)
		(property "Device Type" "DIODE_4_V1-G122-10123-01"
			(at -0.254 2.702306 270)
			(unlocked yes)
			(layer "B.Fab")
			(hide yes)
			(effects
				(font
					(size 0.7874 0.5842)
					(thickness 0.1524)
				)
				(justify mirror)
			)
		)
		(property "User Part Number" "PARTNUM*"
			(at -0.254 3.718306 270)
			(unlocked yes)
			(layer "Cmts.User")
			(hide yes)
			(effects
				(font
					(size 0.7874 0.5842)
					(thickness 0.1524)
				)
				(justify mirror)
			)
		)
		(duplicate_pad_numbers_are_jumpers no)
		(fp_line
			(start -2.0828 1.7018)
			(end 2.0828 1.7018)
			(stroke
				(width 0.1)
				(type default)
			)
			(layer "B.SilkS")
		)
		(fp_line
			(start 2.0828 1.7018)
			(end 2.0828 -1.7018)
			(stroke
				(width 0.1)
				(type default)
			)
			(layer "B.SilkS")
		)
		(fp_line
			(start -2.0828 -1.7018)
			(end -2.0828 1.7018)
			(stroke
				(width 0.1)
				(type default)
			)
			(layer "B.SilkS")
		)
		(fp_line
			(start 2.0828 -1.7018)
			(end -2.0828 -1.7018)
			(stroke
				(width 0.1)
				(type default)
			)
			(layer "B.SilkS")
		)
		(fp_poly
			(pts
				(arc
					(start 2.6162 -1.27)
					(mid 2.6162 -0.508)
					(end 2.6162 -1.27)
				)
			)
			(stroke
				(width 0)
				(type default)
			)
			(fill yes)
			(layer "B.SilkS")
		)
		(fp_rect
			(start -2.3368 1.9304)
			(end 2.3368 -1.9304)
			(stroke
				(width 0)
				(type default)
			)
			(fill no)
			(layer "B.CrtYd")
		)
		(fp_line
			(start -0.6477 1.42875)
			(end 0.6477 1.42875)
			(stroke
				(width 0.1)
				(type default)
			)
			(layer "B.Fab")
		)
		(fp_line
			(start 0.6477 1.42875)
			(end 0.6477 -1.42875)
			(stroke
				(width 0.1)
				(type default)
			)
			(layer "B.Fab")
		)
		(fp_line
			(start -1.143 1.1811)
			(end -0.6477 1.1811)
			(stroke
				(width 0.1)
				(type default)
			)
			(layer "B.Fab")
		)
		(fp_line
			(start -0.6477 1.1811)
			(end -0.6477 0.7239)
			(stroke
				(width 0.1)
				(type default)
			)
			(layer "B.Fab")
		)
		(fp_line
			(start 0.6477 1.1811)
			(end 1.143 1.1811)
			(stroke
				(width 0.1)
				(type default)
			)
			(layer "B.Fab")
		)
		(fp_line
			(start 1.143 1.1811)
			(end 1.143 0.7239)
			(stroke
				(width 0.1)
				(type default)
			)
			(layer "B.Fab")
		)
		(fp_line
			(start -1.143 0.7239)
			(end -1.143 1.1811)
			(stroke
				(width 0.1)
				(type default)
			)
			(layer "B.Fab")
		)
		(fp_line
			(start -0.6477 0.7239)
			(end -1.143 0.7239)
			(stroke
				(width 0.1)
				(type default)
			)
			(layer "B.Fab")
		)
		(fp_line
			(start 0.6477 0.7239)
			(end 0.6477 1.1811)
			(stroke
				(width 0.1)
				(type default)
			)
			(layer "B.Fab")
		)
		(fp_line
			(start 1.143 0.7239)
			(end 0.6477 0.7239)
			(stroke
				(width 0.1)
				(type default)
			)
			(layer "B.Fab")
		)
		(fp_line
			(start 0.6477 -0.3175)
			(end 1.143 -0.3175)
			(stroke
				(width 0.1)
				(type default)
			)
			(layer "B.Fab")
		)
		(fp_line
			(start 1.143 -0.3175)
			(end 1.143 -1.1811)
			(stroke
				(width 0.1)
				(type default)
			)
			(layer "B.Fab")
		)
		(fp_line
			(start -1.143 -0.7239)
			(end -0.6477 -0.7239)
			(stroke
				(width 0.1)
				(type default)
			)
			(layer "B.Fab")
		)
		(fp_line
			(start -0.6477 -0.7239)
			(end -0.6477 -1.1811)
			(stroke
				(width 0.1)
				(type default)
			)
			(layer "B.Fab")
		)
		(fp_line
			(start -1.143 -1.1811)
			(end -1.143 -0.7239)
			(stroke
				(width 0.1)
				(type default)
			)
			(layer "B.Fab")
		)
		(fp_line
			(start -0.6477 -1.1811)
			(end -1.143 -1.1811)
			(stroke
				(width 0.1)
				(type default)
			)
			(layer "B.Fab")
		)
		(fp_line
			(start 0.6477 -1.1811)
			(end 0.6477 -0.3175)
			(stroke
				(width 0.1)
				(type default)
			)
			(layer "B.Fab")
		)
		(fp_line
			(start 1.143 -1.1811)
			(end 0.6477 -1.1811)
			(stroke
				(width 0.1)
				(type default)
			)
			(layer "B.Fab")
		)
		(fp_line
			(start -0.6477 -1.42875)
			(end -0.6477 1.42875)
			(stroke
				(width 0.1)
				(type default)
			)
			(layer "B.Fab")
		)
		(fp_line
			(start 0.6477 -1.42875)
			(end -0.6477 -1.42875)
			(stroke
				(width 0.1)
				(type default)
			)
			(layer "B.Fab")
		)
		(fp_poly
			(pts
				(arc
					(start 0.381 -0.9398)
					(mid 0.381 -0.5588)
					(end 0.381 -0.9398)
				)
			)
			(stroke
				(width 0)
				(type default)
			)
			(fill yes)
			(layer "B.Fab")
		)
		(fp_text user "3"
			(at -1.84023 1.8161 0)
			(unlocked yes)
			(layer "B.SilkS")
			(effects
				(font
					(size 0.7874 0.5842)
					(thickness 0.1524)
				)
				(justify left mirror)
			)
		)
		(fp_text user "2"
			(at 2.85877 0.8001 0)
			(unlocked yes)
			(layer "B.SilkS")
			(effects
				(font
					(size 0.7874 0.5842)
					(thickness 0.1524)
				)
				(justify left mirror)
			)
		)
		(fp_text user "4"
			(at -2.09423 -2.6289 0)
			(unlocked yes)
			(layer "B.SilkS")
			(effects
				(font
					(size 0.7874 0.5842)
					(thickness 0.1524)
				)
				(justify left mirror)
			)
		)
		(fp_text user "3"
			(at -1.76403 0.669036 0)
			(unlocked yes)
			(layer "B.Fab")
			(effects
				(font
					(size 0.7874 0.5842)
					(thickness 0.1524)
				)
				(justify left mirror)
			)
		)
		(fp_text user "2"
			(at 1.83007 0.5842 0)
			(unlocked yes)
			(layer "B.Fab")
			(effects
				(font
					(size 0.7874 0.5842)
					(thickness 0.1524)
				)
				(justify left mirror)
			)
		)
		(fp_text user "4"
			(at -1.78943 -1.261618 0)
			(unlocked yes)
			(layer "B.Fab")
			(effects
				(font
					(size 0.7874 0.5842)
					(thickness 0.1524)
				)
				(justify left mirror)
			)
		)
		(pad "1" smd rect
			(at 1.1049 -0.7493 90)
			(size 1.4478 1.0922)
			(layers "B.Cu" "B.Mask" "B.Paste")
			(net "SG")
		)
		(pad "2" smd rect
			(at 1.1049 0.9525 90)
			(size 1.4478 0.9906)
			(layers "B.Cu" "B.Mask" "B.Paste")
			(net "FT4232_FPGA_TCK")
		)
		(pad "3" smd rect
			(at -1.1049 0.9525 90)
			(size 1.4478 0.9906)
			(layers "B.Cu" "B.Mask" "B.Paste")
			(net "FT4232_FPGA_TDO")
		)
		(pad "4" smd rect
			(at -1.1049 -0.9525 90)
			(size 1.4478 0.9906)
			(layers "B.Cu" "B.Mask" "B.Paste")
			(net "Net_624")
		)
		(zone
			(layer "B.Cu")
			(hatch none 0.5)
			(connect_pads
				(clearance 0)
			)
			(min_thickness 0.25)
			(keepout
				(tracks allowed)
				(vias not_allowed)
				(pads allowed)
				(copperpour not_allowed)
				(footprints allowed)
			)
			(placement
				(enabled no)
				(sheetname "")
			)
			(fill
				(thermal_gap 0.5)
				(thermal_bridge_width 0.5)
				(island_removal_mode 0)
			)
			(polygon
				(pts
					(xy 146.4056 -67.4497) (xy 146.5453 -67.4497) (xy 146.5453 -68.4784) (xy 145.5674 -68.4784) (xy 145.5674 -68.7451)
					(xy 144.653 -68.7451) (xy 144.653 -68.4784) (xy 143.6751 -68.4784) (xy 143.6751 -67.7164) (xy 144.653 -67.7164)
					(xy 144.653 -67.4497) (xy 145.3134 -67.4497) (xy 145.3134 -67.7164) (xy 146.4056 -67.7164)
				)
			)
		)
	)
)
